# S9S_MB_2U (Grand Teton) — schematic netlist excerpt (pin names and nets, part order shuffled) for the footprints in the layout excerpt that follows; sources: Cadence DE-HDL packaged netlist, KiCad conversion of 03242023_DA0F0TMBIJ0_F0T_Motherboard_J_brd_V01_OCP.brd

C1315  Q_CAP  1UF 25V 10% X6S  pkg C0402  page 244 : A = P3V3_AUX ; B = GND
C920  Q_CAP_DIFFBUS  DIFF BUS_0.22UF 6.3V 20% X6S  pkg C0201  page 173 : \1\ = P5E_CPU0_PE0_TX_C_DN<6> ; \2\ = P5E_CPU0_PE0_TX_DN<6>
PC4056  Q_CAP  3900PF 50V 10% EMPTY  pkg C0402  page 156 : A = P12V_OCP_GATE_1 ; B = GND

(kicad_pcb
	(version 20260206)
	(generator "pcbnew")
	(generator_version "10.0")
	(general
		(thickness 1.6)
		(legacy_teardrops no)
	)
	(paper "A4")
	(title_block
		(title "03242023_DA0F0TMBIJ0_F0T_Motherboard_J_brd_V01_OCP.brd")
		(comment 1 "Grand Teton / footprints 921-923 of 6105")
	)
	(layers
		(0 "F.Cu" signal "TOP")
		(4 "In1.Cu" signal "GND")
		(6 "In2.Cu" signal "IN1")
		(8 "In3.Cu" signal "GND1")
		(10 "In4.Cu" signal "IN2")
		(12 "In5.Cu" signal "GND2")
		(14 "In6.Cu" signal "IN3")
		(16 "In7.Cu" signal "GND3")
		(18 "In8.Cu" signal "VCC")
		(20 "In9.Cu" signal "VCC1")
		(22 "In10.Cu" signal "GND4")
		(24 "In11.Cu" signal "IN4")
		(26 "In12.Cu" signal "GND5")
		(28 "In13.Cu" signal "IN5")
		(30 "In14.Cu" signal "GND6")
		(32 "In15.Cu" signal "IN6")
		(34 "In16.Cu" signal "GND7")
		(2 "B.Cu" signal "BOTTOM")
		(9 "F.Adhes" user "F.Adhesive")
		(11 "B.Adhes" user "B.Adhesive")
		(13 "F.Paste" user "Package Geometry/Pastemask Top")
		(15 "B.Paste" user "Package Geometry/Pastemask Bottom")
		(5 "F.SilkS" user "Ref Des/Silkscreen Top")
		(7 "B.SilkS" user "Ref Des/Silkscreen Bottom")
		(1 "F.Mask" user "Board Geometry/Soldermask Top")
		(3 "B.Mask" user "Board Geometry/Soldermask Bottom")
		(17 "Dwgs.User" user "User.Drawings")
		(19 "Cmts.User" user "User.Comments")
		(21 "Eco1.User" user "User.Eco1")
		(23 "Eco2.User" user "User.Eco2")
		(25 "Edge.Cuts" user "Board Geometry/Outline")
		(27 "Margin" user)
		(31 "F.CrtYd" user "Package Geometry/Place Bound Top")
		(29 "B.CrtYd" user "Package Geometry/Place Bound Bottom")
		(35 "F.Fab" user "Ref Des/Assembly Top")
		(33 "B.Fab" user "Ref Des/Assembly Bottom")
	)
	(footprint ""
		(layer "F.Cu")
		(at 453.054212 -23.603458)
		(property "Reference" "PC4056"
			(at 0 0 0)
			(layer "F.SilkS")
			(hide yes)
			(effects
				(font
					(size 1.27 1.27)
				)
			)
		)
		(property "Value" ""
			(at 0 0 0)
			(layer "F.Fab")
			(effects
				(font
					(size 1.27 1.27)
				)
			)
		)
		(duplicate_pad_numbers_are_jumpers no)
		(fp_line
			(start -0.7874 -0.4064)
			(end 0.7874 -0.4064)
			(stroke
				(width 0.1524)
				(type default)
			)
			(layer "F.SilkS")
		)
		(fp_line
			(start -0.7874 0.4064)
			(end -0.7874 -0.4064)
			(stroke
				(width 0.1524)
				(type default)
			)
			(layer "F.SilkS")
		)
		(fp_line
			(start 0.7874 -0.4064)
			(end 0.7874 0.4064)
			(stroke
				(width 0.1524)
				(type default)
			)
			(layer "F.SilkS")
		)
		(fp_line
			(start 0.7874 0.4064)
			(end -0.7874 0.4064)
			(stroke
				(width 0.1524)
				(type default)
			)
			(layer "F.SilkS")
		)
		(fp_line
			(start -0.67945 -0.305054)
			(end -0.12065 -0.305054)
			(stroke
				(width 0.1)
				(type default)
			)
			(layer "F.Fab")
		)
		(fp_line
			(start -0.67945 0.3048)
			(end -0.67945 -0.305054)
			(stroke
				(width 0.1)
				(type default)
			)
			(layer "F.Fab")
		)
		(fp_line
			(start -0.12065 -0.305054)
			(end -0.12065 -0.2794)
			(stroke
				(width 0.1)
				(type default)
			)
			(layer "F.Fab")
		)
		(fp_line
			(start -0.12065 -0.2794)
			(end 0.12065 -0.2794)
			(stroke
				(width 0.1)
				(type default)
			)
			(layer "F.Fab")
		)
		(fp_line
			(start -0.12065 0.2794)
			(end -0.12065 0.3048)
			(stroke
				(width 0.1)
				(type default)
			)
			(layer "F.Fab")
		)
		(fp_line
			(start -0.12065 0.3048)
			(end -0.67945 0.3048)
			(stroke
				(width 0.1)
				(type default)
			)
			(layer "F.Fab")
		)
		(fp_line
			(start 0.120396 0.2794)
			(end -0.12065 0.2794)
			(stroke
				(width 0.1)
				(type default)
			)
			(layer "F.Fab")
		)
		(fp_line
			(start 0.120396 0.3048)
			(end 0.120396 0.2794)
			(stroke
				(width 0.1)
				(type default)
			)
			(layer "F.Fab")
		)
		(fp_line
			(start 0.12065 -0.3048)
			(end 0.67945 -0.3048)
			(stroke
				(width 0.1)
				(type default)
			)
			(layer "F.Fab")
		)
		(fp_line
			(start 0.12065 -0.2794)
			(end 0.12065 -0.3048)
			(stroke
				(width 0.1)
				(type default)
			)
			(layer "F.Fab")
		)
		(fp_line
			(start 0.67945 -0.3048)
			(end 0.67945 0.3048)
			(stroke
				(width 0.1)
				(type default)
			)
			(layer "F.Fab")
		)
		(fp_line
			(start 0.67945 0.3048)
			(end 0.120396 0.3048)
			(stroke
				(width 0.1)
				(type default)
			)
			(layer "F.Fab")
		)
		(pad "1" smd circle
			(at -0.40005 0)
			(size 0 0)
			(layers "F.Cu" "F.Mask" "F.Paste")
			(net "P12V_OCP_GATE_1")
		)
		(pad "2" smd circle
			(at 0.40005 0)
			(size 0 0)
			(layers "F.Cu" "F.Mask" "F.Paste")
			(net "GND")
		)
	)
	(footprint ""
		(layer "F.Cu")
		(at 332.870048 -408.517344 -90)
		(property "Reference" "C920"
			(at 0 0 270)
			(layer "F.SilkS")
			(hide yes)
			(effects
				(font
					(size 1.27 1.27)
				)
			)
		)
		(property "Value" ""
			(at 0 0 270)
			(layer "F.Fab")
			(effects
				(font
					(size 1.27 1.27)
				)
			)
		)
		(duplicate_pad_numbers_are_jumpers no)
		(fp_line
			(start -0.299974 0.150114)
			(end -0.299974 -0.150114)
			(stroke
				(width 0.1)
				(type default)
			)
			(layer "F.Fab")
		)
		(fp_line
			(start 0.299974 0.150114)
			(end -0.299974 0.150114)
			(stroke
				(width 0.1)
				(type default)
			)
			(layer "F.Fab")
		)
		(fp_line
			(start -0.299974 -0.150114)
			(end 0.299974 -0.150114)
			(stroke
				(width 0.1)
				(type default)
			)
			(layer "F.Fab")
		)
		(fp_line
			(start 0.299974 -0.150114)
			(end 0.299974 0.150114)
			(stroke
				(width 0.1)
				(type default)
			)
			(layer "F.Fab")
		)
		(pad "1" smd rect
			(at -0.2667 0 270)
			(size 0.3048 0.381)
			(layers "F.Cu" "F.Mask" "F.Paste")
			(net "P5E_CPU0_PE0_TX_C_DN<6>")
		)
		(pad "2" smd rect
			(at 0.2667 0 270)
			(size 0.3048 0.381)
			(layers "F.Cu" "F.Mask" "F.Paste")
			(net "P5E_CPU0_PE0_TX_DN<6>")
		)
	)
	(footprint ""
		(layer "F.Cu")
		(at 218.12758 -131.973828)
		(property "Reference" "C1315"
			(at 0 0 0)
			(layer "F.SilkS")
			(hide yes)
			(effects
				(font
					(size 1.27 1.27)
				)
			)
		)
		(property "Value" ""
			(at 0 0 0)
			(layer "F.Fab")
			(effects
				(font
					(size 1.27 1.27)
				)
			)
		)
		(duplicate_pad_numbers_are_jumpers no)
		(fp_line
			(start -0.7874 -0.4064)
			(end 0.7874 -0.4064)
			(stroke
				(width 0.1524)
				(type default)
			)
			(layer "F.SilkS")
		)
		(fp_line
			(start -0.7874 0.4064)
			(end -0.7874 -0.4064)
			(stroke
				(width 0.1524)
				(type default)
			)
			(layer "F.SilkS")
		)
		(fp_line
			(start 0.7874 -0.4064)
			(end 0.7874 0.4064)
			(stroke
				(width 0.1524)
				(type default)
			)
			(layer "F.SilkS")
		)
		(fp_line
			(start 0.7874 0.4064)
			(end -0.7874 0.4064)
			(stroke
				(width 0.1524)
				(type default)
			)
			(layer "F.SilkS")
		)
		(fp_line
			(start -0.67945 -0.305054)
			(end -0.12065 -0.305054)
			(stroke
				(width 0.1)
				(type default)
			)
			(layer "F.Fab")
		)
		(fp_line
			(start -0.67945 0.3048)
			(end -0.67945 -0.305054)
			(stroke
				(width 0.1)
				(type default)
			)
			(layer "F.Fab")
		)
		(fp_line
			(start -0.12065 -0.305054)
			(end -0.12065 -0.2794)
			(stroke
				(width 0.1)
				(type default)
			)
			(layer "F.Fab")
		)
		(fp_line
			(start -0.12065 -0.2794)
			(end 0.12065 -0.2794)
			(stroke
				(width 0.1)
				(type default)
			)
			(layer "F.Fab")
		)
		(fp_line
			(start -0.12065 0.2794)
			(end -0.12065 0.3048)
			(stroke
				(width 0.1)
				(type default)
			)
			(layer "F.Fab")
		)
		(fp_line
			(start -0.12065 0.3048)
			(end -0.67945 0.3048)
			(stroke
				(width 0.1)
				(type default)
			)
			(layer "F.Fab")
		)
		(fp_line
			(start 0.120396 0.2794)
			(end -0.12065 0.2794)
			(stroke
				(width 0.1)
				(type default)
			)
			(layer "F.Fab")
		)
		(fp_line
			(start 0.120396 0.3048)
			(end 0.120396 0.2794)
			(stroke
				(width 0.1)
				(type default)
			)
			(layer "F.Fab")
		)
		(fp_line
			(start 0.12065 -0.3048)
			(end 0.67945 -0.3048)
			(stroke
				(width 0.1)
				(type default)
			)
			(layer "F.Fab")
		)
		(fp_line
			(start 0.12065 -0.2794)
			(end 0.12065 -0.3048)
			(stroke
				(width 0.1)
				(type default)
			)
			(layer "F.Fab")
		)
		(fp_line
			(start 0.67945 -0.3048)
			(end 0.67945 0.3048)
			(stroke
				(width 0.1)
				(type default)
			)
			(layer "F.Fab")
		)
		(fp_line
			(start 0.67945 0.3048)
			(end 0.120396 0.3048)
			(stroke
				(width 0.1)
				(type default)
			)
			(layer "F.Fab")
		)
		(pad "1" smd circle
			(at -0.40005 0)
			(size 0 0)
			(layers "F.Cu" "F.Mask" "F.Paste")
			(net "P3V3_AUX")
		)
		(pad "2" smd circle
			(at 0.40005 0)
			(size 0 0)
			(layers "F.Cu" "F.Mask" "F.Paste")
			(net "GND")
		)
	)
)
